FILE_TYPE = MACRO_DRAWING;
SET COLOR_WIRE YELLOW;
SET COLOR_PROP ORANGE;
SET COLOR_DOT WHITE;
SET COLOR_ARC YELLOW;
SET COLOR_BODY GREEN;
SET COLOR_NOTE PURPLE;
SET PROP_DISPLAY VALUE;
SET PAGE_NUMBER P346;
FORCEADD PCA9306DP1..1
R 2
(725 3400);
FORCEPROP 1 LAST LOCATION U98
J 2
(925 3705);
DISPLAY 0.680851 (925 3705);
PAINT GREEN (925 3705);
FORCEPROP 0 LAST $SEC 1
J 0
(950 4000);
DISPLAY 0.680851 (950 4000);
PAINT MONO (950 4000);
DISPLAY INVISIBLE (950 4000);
FORCEPROP 2 LAST CDS_SEC 1
J 0
(950 4000);
DISPLAY 1.021277 (950 4000);
DISPLAY INVISIBLE (950 4000);
FORCEPROP 0 LASTPIN (1075 3275) $PN 8
J 0
(1085 3285);
DISPLAY 0.680851 (1085 3285);
PAINT MONO (1085 3285);
FORCEPROP 0 LASTPIN (475 3275) $PN 1
J 2
(465 3285);
DISPLAY 0.680851 (465 3285);
PAINT MONO (465 3285);
FORCEPROP 0 LASTPIN (1075 3375) $PN 3
J 0
(1085 3385);
DISPLAY 0.680851 (1085 3385);
PAINT MONO (1085 3385);
FORCEPROP 0 LASTPIN (375 3375) $PN 6
J 2
(365 3385);
DISPLAY 0.680851 (365 3385);
PAINT MONO (365 3385);
FORCEPROP 0 LASTPIN (1075 3425) $PN 4
J 0
(1085 3435);
DISPLAY 0.680851 (1085 3435);
PAINT MONO (1085 3435);
FORCEPROP 0 LASTPIN (375 3425) $PN 5
J 2
(365 3435);
DISPLAY 0.680851 (365 3435);
PAINT MONO (365 3435);
FORCEPROP 0 LASTPIN (1075 3525) $PN 2
J 0
(1085 3535);
DISPLAY 0.680851 (1085 3535);
PAINT MONO (1085 3535);
FORCEPROP 0 LASTPIN (375 3525) $PN 7
J 2
(365 3535);
DISPLAY 0.680851 (365 3535);
PAINT MONO (365 3535);
FORCEPROP 1 LAST MATERIAL IC
J 2
(924 3600);
DISPLAY 0.723404 (924 3600);
PAINT GREEN (924 3600);
FORCEPROP 2 LAST VALUE PCA9306DP1
J 2
(950 3900);
DISPLAY 1.021277 (950 3900);
FORCEPROP 2 LAST PART_TYPE SMLF
J 2
(950 3950);
DISPLAY 1.021277 (950 3950);
FORCEPROP 1 LAST PART_NUMBER AL009306K04
J 2
(924 3650);
DISPLAY 0.723404 (924 3650);
PAINT GREEN (924 3650);
DISPLAY INVISIBLE (924 3650);
FORCEPROP 1 LAST PATH I27
J 2
(725 3400);
DISPLAY 0.723404 (725 3400);
PAINT GREEN (725 3400);
DISPLAY INVISIBLE (725 3400);
FORCEPROP 1 LAST CDS_LMAN_SYM_OUTLINE -200,175,200,-175
J 2
(725 3400);
DISPLAY 0.468085 (725 3400);
PAINT GREEN (725 3400);
DISPLAY INVISIBLE (725 3400);
FORCEPROP 1 LAST NEEDS_NO_SIZE TRUE
J 2
(725 3399);
DISPLAY 0.468085 (725 3399);
PAINT GREEN (725 3399);
DISPLAY INVISIBLE (725 3399);
FORCEPROP 2 LAST CDS_LIB pure_quanta
J 0
(725 3400);
DISPLAY INVISIBLE (725 3400);
FORCEADD Q_CAP..1
(1400 3800);
FORCEPROP 1 LAST LOCATION C1323
J 0
(1450 3900);
DISPLAY 0.978723 (1450 3900);
FORCEPROP 2 LAST $SEC 1
J 0
(1450 4000);
DISPLAY 0.680851 (1450 4000);
PAINT MONO (1450 4000);
DISPLAY INVISIBLE (1450 4000);
FORCEPROP 2 LAST CDS_SEC 1
J 0
(1450 4000);
DISPLAY 1.021277 (1450 4000);
DISPLAY INVISIBLE (1450 4000);
FORCEPROP 1 LASTPIN (1400 3900) $PN 1
J 0
(1410 3880);
DISPLAY 0.787234 (1410 3880);
FORCEPROP 1 LASTPIN (1400 3700) $PN 2
J 0
(1410 3680);
DISPLAY 0.787234 (1410 3680);
FORCEPROP 1 LAST MATERIAL X7R
J 0
(1450 3700);
DISPLAY 0.510638 (1450 3700);
FORCEPROP 1 LAST PACK_TYPE 0402
J 0
(1450 3600);
DISPLAY 0.510638 (1450 3600);
FORCEPROP 1 LAST TOLERANCE 10%
J 0
(1450 3750);
DISPLAY 0.510638 (1450 3750);
FORCEPROP 1 LAST VOLTAGE 25V
J 0
(1450 3800);
DISPLAY 0.510638 (1450 3800);
FORCEPROP 1 LAST VALUE 0.1UF
J 0
(1450 3850);
DISPLAY 0.510638 (1450 3850);
FORCEPROP 1 LAST PART_NUMBER CH4104K1B00
J 0
(1450 3650);
DISPLAY 0.510638 (1450 3650);
DISPLAY INVISIBLE (1450 3650);
FORCEPROP 1 LAST PATH I28
J 0
(1450 3950);
DISPLAY 0.978723 (1450 3950);
PAINT WHITE (1450 3950);
DISPLAY INVISIBLE (1450 3950);
FORCEPROP 2 LAST CDS_LIB pure_quanta
J 0
(1400 3800);
PAINT MONO (1400 3800);
DISPLAY INVISIBLE (1400 3800);
FORCEADD UNIVERSAL_POWER..1
(1225 4100);
FORCEPROP 3 LASTPIN (1225 4050) SIG_NAME P1V8_AUX\g
J 0
(1235 4060);
DISPLAY 0.659574 (1235 4060);
PAINT MONO (1235 4060);
DISPLAY INVISIBLE (1235 4060);
FORCEPROP 1 LAST HDL_POWER P1V8_AUX
J 1
(1225 4150);
DISPLAY 0.872340 (1225 4150);
PAINT GREEN (1225 4150);
FORCEPROP 1 LAST PATH I29
J 0
(1275 4125);
DISPLAY 0.872340 (1275 4125);
PAINT AQUA (1275 4125);
DISPLAY INVISIBLE (1275 4125);
FORCEPROP 2 LAST CDS_LIB pure_quanta_power
J 0
(1225 4100);
PAINT MONO (1225 4100);
DISPLAY INVISIBLE (1225 4100);
FORCEADD UNIVERSAL_GND..1
(1400 3575);
FORCEPROP 3 LASTPIN (1400 3625) SIG_NAME GND\g
J 0
(1410 3635);
DISPLAY 0.659574 (1410 3635);
PAINT MONO (1410 3635);
DISPLAY INVISIBLE (1410 3635);
FORCEPROP 1 LAST PATH I30
J 0
(1475 3575);
DISPLAY 0.872340 (1475 3575);
PAINT AQUA (1475 3575);
DISPLAY INVISIBLE (1475 3575);
FORCEPROP 1 LAST HDL_POWER GND
J 1
(1425 3500);
DISPLAY 0.872340 (1425 3500);
PAINT GREEN (1425 3500);
DISPLAY INVISIBLE (1425 3500);
FORCEPROP 2 LAST CDS_LIB pure_quanta_power
J 0
(1400 3575);
PAINT MONO (1400 3575);
DISPLAY INVISIBLE (1400 3575);
FORCEADD UNIVERSAL_GND..1
(350 3150);
FORCEPROP 3 LASTPIN (350 3200) SIG_NAME GND\g
J 0
(360 3210);
DISPLAY 0.659574 (360 3210);
PAINT MONO (360 3210);
DISPLAY INVISIBLE (360 3210);
FORCEPROP 1 LAST PATH I38
J 0
(425 3150);
DISPLAY 0.872340 (425 3150);
PAINT AQUA (425 3150);
DISPLAY INVISIBLE (425 3150);
FORCEPROP 1 LAST HDL_POWER GND
J 1
(375 3075);
DISPLAY 0.872340 (375 3075);
PAINT GREEN (375 3075);
DISPLAY INVISIBLE (375 3075);
FORCEPROP 2 LAST CDS_LIB pure_quanta_power
J 0
(350 3150);
PAINT MONO (350 3150);
DISPLAY INVISIBLE (350 3150);
FORCEADD Q_RES..2
(2250 3775);
FORCEPROP 1 LAST LOCATION R1702
J 0
(2295 3900);
DISPLAY 0.638298 (2295 3900);
FORCEPROP 2 LAST $SEC 1
J 0
(2300 4000);
DISPLAY 0.680851 (2300 4000);
PAINT MONO (2300 4000);
DISPLAY INVISIBLE (2300 4000);
FORCEPROP 2 LAST CDS_SEC 1
J 0
(2300 4000);
DISPLAY 1.021277 (2300 4000);
DISPLAY INVISIBLE (2300 4000);
FORCEPROP 1 LASTPIN (2250 3875) $PN 1
J 0
(2255 3837);
DISPLAY 0.787234 (2255 3837);
FORCEPROP 1 LASTPIN (2250 3675) $PN 2
J 0
(2255 3685);
DISPLAY 0.787234 (2255 3685);
FORCEPROP 1 LAST PACK_TYPE 0402LF
J 0
(2290 3650);
DISPLAY 0.638298 (2290 3650);
FORCEPROP 1 LAST VALUE 4.7K
J 0
(2295 3850);
DISPLAY 0.638298 (2295 3850);
FORCEPROP 1 LAST TOLERANCE 5%
J 0
(2295 3800);
DISPLAY 0.638298 (2295 3800);
FORCEPROP 1 LAST MATERIAL CHIP
J 0
(2290 3700);
DISPLAY 0.638298 (2290 3700);
FORCEPROP 1 LAST WATTAGE 1/16W
J 0
(2290 3750);
DISPLAY 0.638298 (2290 3750);
FORCEPROP 1 LAST PART_NUMBER CS24702JB10
J 0
(2290 3600);
DISPLAY 0.638298 (2290 3600);
DISPLAY INVISIBLE (2290 3600);
FORCEPROP 1 LAST PATH I43
J 0
(2300 3950);
DISPLAY 0.978723 (2300 3950);
PAINT WHITE (2300 3950);
DISPLAY INVISIBLE (2300 3950);
FORCEPROP 2 LAST CDS_LIB pure_quanta
J 0
(2250 3775);
PAINT MONO (2250 3775);
DISPLAY INVISIBLE (2250 3775);
FORCEADD Q_RES..2
(2500 3775);
FORCEPROP 1 LAST LOCATION R1703
J 0
(2545 3900);
DISPLAY 0.638298 (2545 3900);
FORCEPROP 2 LAST $SEC 1
J 0
(2550 4000);
DISPLAY 0.680851 (2550 4000);
PAINT MONO (2550 4000);
DISPLAY INVISIBLE (2550 4000);
FORCEPROP 2 LAST CDS_SEC 1
J 0
(2550 4000);
DISPLAY 1.021277 (2550 4000);
DISPLAY INVISIBLE (2550 4000);
FORCEPROP 1 LASTPIN (2500 3875) $PN 1
J 0
(2505 3837);
DISPLAY 0.787234 (2505 3837);
FORCEPROP 1 LASTPIN (2500 3675) $PN 2
J 0
(2505 3685);
DISPLAY 0.787234 (2505 3685);
FORCEPROP 1 LAST PACK_TYPE 0402LF
J 0
(2540 3650);
DISPLAY 0.638298 (2540 3650);
FORCEPROP 1 LAST MATERIAL CHIP
J 0
(2540 3700);
DISPLAY 0.638298 (2540 3700);
FORCEPROP 1 LAST TOLERANCE 5%
J 0
(2545 3800);
DISPLAY 0.638298 (2545 3800);
FORCEPROP 1 LAST VALUE 4.7K
J 0
(2545 3850);
DISPLAY 0.638298 (2545 3850);
FORCEPROP 1 LAST WATTAGE 1/16W
J 0
(2540 3750);
DISPLAY 0.638298 (2540 3750);
FORCEPROP 1 LAST PART_NUMBER CS24702JB10
J 0
(2540 3600);
DISPLAY 0.638298 (2540 3600);
DISPLAY INVISIBLE (2540 3600);
FORCEPROP 1 LAST PATH I45
J 0
(2550 3950);
DISPLAY 0.978723 (2550 3950);
PAINT WHITE (2550 3950);
DISPLAY INVISIBLE (2550 3950);
FORCEPROP 2 LAST CDS_LIB pure_quanta
J 0
(2500 3775);
PAINT MONO (2500 3775);
DISPLAY INVISIBLE (2500 3775);
FORCEADD UNIVERSAL_POWER..1
(2250 4100);
FORCEPROP 3 LASTPIN (2250 4050) SIG_NAME P1V8_AUX\g
J 0
(2260 4060);
DISPLAY 0.659574 (2260 4060);
PAINT MONO (2260 4060);
DISPLAY INVISIBLE (2260 4060);
FORCEPROP 1 LAST HDL_POWER P1V8_AUX
J 1
(2250 4150);
DISPLAY 0.872340 (2250 4150);
PAINT GREEN (2250 4150);
FORCEPROP 1 LAST PATH I47
J 0
(2300 4125);
DISPLAY 0.872340 (2300 4125);
PAINT AQUA (2300 4125);
DISPLAY INVISIBLE (2300 4125);
FORCEPROP 2 LAST CDS_LIB pure_quanta_power
J 0
(2250 4100);
PAINT MONO (2250 4100);
DISPLAY INVISIBLE (2250 4100);
FORCEADD UNIVERSAL_POWER..1
(0 4125);
FORCEPROP 3 LASTPIN (0 4075) SIG_NAME P3V3_AUX\g
J 0
(10 4085);
DISPLAY 0.659574 (10 4085);
PAINT MONO (10 4085);
DISPLAY INVISIBLE (10 4085);
FORCEPROP 1 LAST HDL_POWER P3V3_AUX
J 1
(0 4175);
DISPLAY 0.872340 (0 4175);
PAINT GREEN (0 4175);
FORCEPROP 1 LAST PATH I51
J 0
(50 4150);
DISPLAY 0.872340 (50 4150);
PAINT AQUA (50 4150);
DISPLAY INVISIBLE (50 4150);
FORCEPROP 2 LAST CDS_LIB pure_quanta_power
J 0
(0 4125);
PAINT MONO (0 4125);
DISPLAY INVISIBLE (0 4125);
FORCEADD Q_CAP..1
R 2
(-425 3775);
FORCEPROP 1 LAST LOCATION C1305
J 2
(-475 3875);
DISPLAY 0.978723 (-475 3875);
FORCEPROP 2 LAST $SEC 1
J 0
(-475 3975);
DISPLAY 0.680851 (-475 3975);
PAINT MONO (-475 3975);
DISPLAY INVISIBLE (-475 3975);
FORCEPROP 2 LAST CDS_SEC 1
J 0
(-475 3975);
DISPLAY 1.021277 (-475 3975);
DISPLAY INVISIBLE (-475 3975);
FORCEPROP 1 LASTPIN (-425 3875) $PN 1
J 2
(-435 3855);
DISPLAY 0.787234 (-435 3855);
FORCEPROP 1 LASTPIN (-425 3675) $PN 2
J 2
(-435 3655);
DISPLAY 0.787234 (-435 3655);
FORCEPROP 1 LAST TOLERANCE 10%
J 2
(-475 3725);
DISPLAY 0.510638 (-475 3725);
FORCEPROP 1 LAST VALUE 0.1UF
J 2
(-475 3825);
DISPLAY 0.510638 (-475 3825);
FORCEPROP 1 LAST VOLTAGE 25V
J 2
(-475 3775);
DISPLAY 0.510638 (-475 3775);
FORCEPROP 1 LAST MATERIAL X7R
J 2
(-475 3675);
DISPLAY 0.510638 (-475 3675);
FORCEPROP 1 LAST PACK_TYPE 0402
J 2
(-475 3575);
DISPLAY 0.510638 (-475 3575);
FORCEPROP 1 LAST PART_NUMBER CH4104K1B00
J 2
(-475 3625);
DISPLAY 0.510638 (-475 3625);
DISPLAY INVISIBLE (-475 3625);
FORCEPROP 1 LAST PATH I52
J 2
(-475 3925);
DISPLAY 0.978723 (-475 3925);
PAINT WHITE (-475 3925);
DISPLAY INVISIBLE (-475 3925);
FORCEPROP 2 LAST CDS_LIB pure_quanta
J 2
(-425 3775);
PAINT MONO (-425 3775);
DISPLAY INVISIBLE (-425 3775);
FORCEADD UNIVERSAL_GND..1
(-425 3575);
FORCEPROP 3 LASTPIN (-425 3625) SIG_NAME GND\g
J 0
(-415 3635);
DISPLAY 0.659574 (-415 3635);
PAINT MONO (-415 3635);
DISPLAY INVISIBLE (-415 3635);
FORCEPROP 1 LAST PATH I53
J 0
(-350 3575);
DISPLAY 0.872340 (-350 3575);
PAINT AQUA (-350 3575);
DISPLAY INVISIBLE (-350 3575);
FORCEPROP 1 LAST HDL_POWER GND
J 1
(-400 3500);
DISPLAY 0.872340 (-400 3500);
PAINT GREEN (-400 3500);
DISPLAY INVISIBLE (-400 3500);
FORCEPROP 2 LAST CDS_LIB pure_quanta_power
J 0
(-425 3575);
PAINT MONO (-425 3575);
DISPLAY INVISIBLE (-425 3575);
FORCEADD OFFPAGE..6
(-1000 3425);
FORCEPROP 2 LAST $XR0 251 
J 0
(-1280 3425);
DISPLAY 0.638298 (-1280 3425);
PAINT MONO (-1280 3425);
FORCEPROP 2 LAST PATH I54
J 0
(-1275 3475);
DISPLAY 1.021277 (-1275 3475);
DISPLAY INVISIBLE (-1275 3475);
FORCEPROP 1 LAST COMMENT_BODY TRUE
J 0
(-900 3350);
DISPLAY 0.872340 (-900 3350);
PAINT GREEN (-900 3350);
DISPLAY INVISIBLE (-900 3350);
FORCEPROP 1 LAST OFFPAGE TRUE
J 0
(-675 3300);
DISPLAY 0.872340 (-675 3300);
DISPLAY INVISIBLE (-675 3300);
FORCEPROP 2 LAST CDS_LIB standard
J 0
(-1000 3425);
PAINT MONO (-1000 3425);
DISPLAY INVISIBLE (-1000 3425);
FORCEADD OFFPAGE..1
(-1000 3375);
FORCEPROP 2 LAST $XR0 251 
J 0
(-1282 3375);
DISPLAY 0.638298 (-1282 3375);
PAINT MONO (-1282 3375);
FORCEPROP 2 LAST PATH I55
J 0
(-1275 3425);
DISPLAY 1.021277 (-1275 3425);
DISPLAY INVISIBLE (-1275 3425);
FORCEPROP 1 LAST COMMENT_BODY TRUE
J 0
(-875 3275);
DISPLAY 0.872340 (-875 3275);
PAINT GREEN (-875 3275);
DISPLAY INVISIBLE (-875 3275);
FORCEPROP 1 LAST OFFPAGE TRUE
J 0
(-675 3250);
DISPLAY 0.872340 (-675 3250);
DISPLAY INVISIBLE (-675 3250);
FORCEPROP 2 LAST CDS_LIB standard
J 0
(-1000 3375);
PAINT MONO (-1000 3375);
DISPLAY INVISIBLE (-1000 3375);
FORCEADD Q_RES..1
(2800 3425);
FORCEPROP 1 LAST LOCATION R2410
J 0
(2575 3425);
DISPLAY 0.638298 (2575 3425);
FORCEPROP 0 LAST $SEC 1
J 0
(2900 3550);
DISPLAY 0.680851 (2900 3550);
PAINT MONO (2900 3550);
DISPLAY INVISIBLE (2900 3550);
FORCEPROP 0 LAST CDS_SEC 1
J 0
(2900 3550);
DISPLAY 1.021277 (2900 3550);
DISPLAY INVISIBLE (2900 3550);
FORCEPROP 1 LASTPIN (2700 3425) $PN 1
J 0
(2712 3437);
DISPLAY 0.787234 (2712 3437);
PAINT MONO (2712 3437);
FORCEPROP 1 LASTPIN (2900 3425) $PN 2
J 0
(2862 3437);
DISPLAY 0.787234 (2862 3437);
PAINT MONO (2862 3437);
FORCEPROP 1 LAST WATTAGE 1/16W
J 2
(2900 3525);
DISPLAY 0.404255 (2900 3525);
FORCEPROP 1 LAST MATERIAL CHIP
J 0
(3100 3425);
DISPLAY 0.510638 (3100 3425);
FORCEPROP 1 LAST VALUE 33.2
J 2
(3000 3425);
DISPLAY 0.510638 (3000 3425);
FORCEPROP 1 LAST PACK_TYPE 0402LF
J 0
(2675 3525);
DISPLAY 0.404255 (2675 3525);
FORCEPROP 1 LAST TOLERANCE 1%
J 0
(3025 3425);
DISPLAY 0.510638 (3025 3425);
FORCEPROP 1 LAST PART_NUMBER CS03322FB03
J 0
(2675 3475);
DISPLAY 0.404255 (2675 3475);
DISPLAY INVISIBLE (2675 3475);
FORCEPROP 1 LAST PATH I65
J 0
(2750 3575);
DISPLAY 0.978723 (2750 3575);
PAINT WHITE (2750 3575);
DISPLAY INVISIBLE (2750 3575);
FORCEPROP 2 LAST CDS_LIB pure_quanta
J 0
(2800 3425);
DISPLAY INVISIBLE (2800 3425);
FORCEADD Q_RES..1
(2800 3375);
FORCEPROP 1 LAST LOCATION R2411
J 0
(2575 3375);
DISPLAY 0.638298 (2575 3375);
FORCEPROP 0 LAST $SEC 1
J 0
(2575 3425);
DISPLAY 0.680851 (2575 3425);
PAINT MONO (2575 3425);
DISPLAY INVISIBLE (2575 3425);
FORCEPROP 0 LAST CDS_SEC 1
J 0
(2575 3425);
DISPLAY 1.021277 (2575 3425);
DISPLAY INVISIBLE (2575 3425);
FORCEPROP 1 LASTPIN (2700 3375) $PN 1
J 0
(2712 3387);
DISPLAY 0.787234 (2712 3387);
PAINT MONO (2712 3387);
FORCEPROP 1 LASTPIN (2900 3375) $PN 2
J 0
(2862 3387);
DISPLAY 0.787234 (2862 3387);
PAINT MONO (2862 3387);
FORCEPROP 1 LAST MATERIAL CHIP
J 0
(3100 3375);
DISPLAY 0.510638 (3100 3375);
FORCEPROP 1 LAST VALUE 33.2
J 2
(3000 3375);
DISPLAY 0.510638 (3000 3375);
FORCEPROP 1 LAST TOLERANCE 1%
J 0
(3025 3375);
DISPLAY 0.510638 (3025 3375);
FORCEPROP 1 LAST PART_NUMBER CS03322FB03
J 0
(2675 3425);
DISPLAY 0.404255 (2675 3425);
DISPLAY INVISIBLE (2675 3425);
FORCEPROP 1 LAST PATH I66
J 0
(2750 3525);
DISPLAY 0.978723 (2750 3525);
PAINT WHITE (2750 3525);
DISPLAY INVISIBLE (2750 3525);
FORCEPROP 2 LAST CDS_LIB pure_quanta
J 0
(2800 3375);
DISPLAY INVISIBLE (2800 3375);
FORCEPROP 1 LAST PACK_TYPE 0402LF
J 0
(2675 3475);
DISPLAY 0.404255 (2675 3475);
DISPLAY INVISIBLE (2675 3475);
FORCEPROP 1 LAST WATTAGE 1/16W
J 2
(2900 3475);
DISPLAY 0.404255 (2900 3475);
DISPLAY INVISIBLE (2900 3475);
FORCEADD OFFPAGE..3
(4125 3425);
FORCEPROP 2 LAST $XR0 144 
J 0
(4339 3425);
DISPLAY 0.638298 (4339 3425);
PAINT MONO (4339 3425);
FORCEPROP 2 LAST PATH I67
J 0
(4350 3475);
DISPLAY 1.021277 (4350 3475);
DISPLAY INVISIBLE (4350 3475);
FORCEPROP 1 LAST COMMENT_BODY TRUE
J 0
(4075 3325);
DISPLAY 0.872340 (4075 3325);
PAINT GREEN (4075 3325);
DISPLAY INVISIBLE (4075 3325);
FORCEPROP 1 LAST OFFPAGE TRUE
J 0
(4450 3300);
DISPLAY 0.872340 (4450 3300);
PAINT GREEN (4450 3300);
DISPLAY INVISIBLE (4450 3300);
FORCEPROP 2 LAST CDS_LIB standard
J 0
(4125 3425);
PAINT MONO (4125 3425);
DISPLAY INVISIBLE (4125 3425);
FORCEADD OFFPAGE..2
(4125 3375);
FORCEPROP 2 LAST $XR0 144 
J 0
(4344 3375);
DISPLAY 0.638298 (4344 3375);
PAINT MONO (4344 3375);
FORCEPROP 2 LAST PATH I68
J 0
(4350 3425);
DISPLAY 1.021277 (4350 3425);
DISPLAY INVISIBLE (4350 3425);
FORCEPROP 1 LAST COMMENT_BODY TRUE
J 0
(4080 3280);
DISPLAY 0.872340 (4080 3280);
PAINT GREEN (4080 3280);
DISPLAY INVISIBLE (4080 3280);
FORCEPROP 1 LAST OFFPAGE TRUE
J 0
(4450 3250);
DISPLAY 0.872340 (4450 3250);
PAINT GREEN (4450 3250);
DISPLAY INVISIBLE (4450 3250);
FORCEPROP 2 LAST CDS_LIB standard
J 0
(4125 3375);
DISPLAY INVISIBLE (4125 3375);
FORCEADD Q_RES..1
(2300 3100);
FORCEPROP 1 LAST LOCATION R2476
J 0
(2075 3100);
DISPLAY 0.787234 (2075 3100);
FORCEPROP 0 LAST $SEC 1
J 0
(2500 3250);
DISPLAY 0.680851 (2500 3250);
PAINT MONO (2500 3250);
DISPLAY INVISIBLE (2500 3250);
FORCEPROP 0 LAST CDS_SEC 1
J 0
(2500 3250);
DISPLAY 1.021277 (2500 3250);
DISPLAY INVISIBLE (2500 3250);
FORCEPROP 1 LASTPIN (2200 3100) $PN 1
J 0
(2212 3112);
DISPLAY 0.787234 (2212 3112);
PAINT MONO (2212 3112);
FORCEPROP 1 LASTPIN (2400 3100) $PN 2
J 0
(2362 3112);
DISPLAY 0.787234 (2362 3112);
PAINT MONO (2362 3112);
FORCEPROP 1 LAST MATERIAL EMPTY
J 0
(2600 3100);
DISPLAY 0.510638 (2600 3100);
PAINT RED (2600 3100);
FORCEPROP 1 LAST WATTAGE 1/16W
J 2
(2500 3225);
DISPLAY 0.510638 (2500 3225);
FORCEPROP 1 LAST PACK_TYPE 0402LF
J 0
(2200 3225);
DISPLAY 0.510638 (2200 3225);
FORCEPROP 1 LAST TOLERANCE 1%
J 0
(2525 3100);
DISPLAY 0.510638 (2525 3100);
FORCEPROP 1 LAST VALUE 200K
J 2
(2500 3100);
DISPLAY 0.510638 (2500 3100);
FORCEPROP 1 LAST PART_NUMBER CS42002FB05
J 0
(2200 3175);
DISPLAY 0.510638 (2200 3175);
DISPLAY INVISIBLE (2200 3175);
FORCEPROP 1 LAST PATH I70
J 0
(2250 3250);
DISPLAY 0.978723 (2250 3250);
PAINT WHITE (2250 3250);
DISPLAY INVISIBLE (2250 3250);
FORCEPROP 2 LAST CDS_LIB pure_quanta
J 0
(2300 3100);
DISPLAY INVISIBLE (2300 3100);
FORCEADD OFFPAGE..4
(3625 3100);
FORCEPROP 2 LAST $XR0 270 
J 0
(3811 3100);
DISPLAY 0.638298 (3811 3100);
PAINT MONO (3811 3100);
FORCEPROP 2 LAST $XR1 81 
J 0
(3931 3100);
DISPLAY 0.638298 (3931 3100);
PAINT MONO (3931 3100);
FORCEPROP 2 LAST $XR2 255 
J 0
(4021 3100);
DISPLAY 0.638298 (4021 3100);
PAINT MONO (4021 3100);
FORCEPROP 2 LAST $XR3 271 
J 0
(4141 3100);
DISPLAY 0.638298 (4141 3100);
PAINT MONO (4141 3100);
FORCEPROP 2 LAST PATH I71
J 0
(3850 3150);
DISPLAY 1.021277 (3850 3150);
DISPLAY INVISIBLE (3850 3150);
FORCEPROP 1 LAST COMMENT_BODY TRUE
J 0
(3600 3000);
DISPLAY 0.872340 (3600 3000);
PAINT GREEN (3600 3000);
DISPLAY INVISIBLE (3600 3000);
FORCEPROP 1 LAST OFFPAGE TRUE
J 0
(3950 2975);
DISPLAY 0.872340 (3950 2975);
DISPLAY INVISIBLE (3950 2975);
FORCEPROP 2 LAST CDS_LIB standard
J 0
(3625 3100);
DISPLAY INVISIBLE (3625 3100);
FORCEADD Q_RES..2
(0 3750);
FORCEPROP 1 LAST LOCATION R1700
J 0
(45 3875);
DISPLAY 0.638298 (45 3875);
FORCEPROP 0 LAST $SEC 1
J 0
(50 3925);
DISPLAY 0.680851 (50 3925);
PAINT MONO (50 3925);
DISPLAY INVISIBLE (50 3925);
FORCEPROP 2 LAST CDS_SEC 1
J 0
(50 3975);
DISPLAY 1.021277 (50 3975);
DISPLAY INVISIBLE (50 3975);
FORCEPROP 1 LASTPIN (0 3850) $PN 1
J 0
(5 3812);
DISPLAY 0.787234 (5 3812);
PAINT MONO (5 3812);
FORCEPROP 1 LASTPIN (0 3650) $PN 2
J 0
(5 3660);
DISPLAY 0.787234 (5 3660);
PAINT MONO (5 3660);
FORCEPROP 1 LAST TOLERANCE 1%
J 0
(45 3775);
DISPLAY 0.638298 (45 3775);
FORCEPROP 1 LAST PACK_TYPE 0402LF
J 0
(40 3575);
DISPLAY 0.638298 (40 3575);
FORCEPROP 1 LAST WATTAGE 1/16W
J 0
(40 3725);
DISPLAY 0.638298 (40 3725);
FORCEPROP 1 LAST VALUE 200K
J 0
(45 3825);
DISPLAY 0.638298 (45 3825);
FORCEPROP 1 LAST MATERIAL CHIP
J 0
(40 3675);
DISPLAY 0.638298 (40 3675);
FORCEPROP 1 LAST PART_NUMBER CS42002FB05
J 0
(40 3625);
DISPLAY 0.638298 (40 3625);
DISPLAY INVISIBLE (40 3625);
FORCEPROP 1 LAST PATH I72
J 0
(50 3925);
DISPLAY 0.978723 (50 3925);
PAINT WHITE (50 3925);
DISPLAY INVISIBLE (50 3925);
FORCEPROP 2 LAST CDS_LIB pure_quanta
J 0
(0 3750);
DISPLAY INVISIBLE (0 3750);
FORCEADD OFFPAGE..3
(4050 1225);
FORCEPROP 2 LAST $XR0 145 
J 0
(4264 1225);
DISPLAY 0.638298 (4264 1225);
PAINT MONO (4264 1225);
FORCEPROP 2 LAST PATH I73
J 0
(4275 1275);
DISPLAY 1.021277 (4275 1275);
DISPLAY INVISIBLE (4275 1275);
FORCEPROP 1 LAST COMMENT_BODY TRUE
J 0
(4000 1125);
DISPLAY 0.872340 (4000 1125);
PAINT GREEN (4000 1125);
DISPLAY INVISIBLE (4000 1125);
FORCEPROP 1 LAST OFFPAGE TRUE
J 0
(4375 1100);
DISPLAY 0.872340 (4375 1100);
PAINT GREEN (4375 1100);
DISPLAY INVISIBLE (4375 1100);
FORCEPROP 2 LAST CDS_LIB standard
J 0
(4050 1225);
PAINT MONO (4050 1225);
DISPLAY INVISIBLE (4050 1225);
FORCEADD OFFPAGE..2
(4050 1125);
FORCEPROP 2 LAST $XR0 145 
J 0
(4239 1125);
DISPLAY 0.638298 (4239 1125);
PAINT MONO (4239 1125);
FORCEPROP 2 LAST PATH I74
J 0
(4275 1175);
DISPLAY 1.021277 (4275 1175);
DISPLAY INVISIBLE (4275 1175);
FORCEPROP 1 LAST COMMENT_BODY TRUE
J 0
(4005 1030);
DISPLAY 0.872340 (4005 1030);
PAINT GREEN (4005 1030);
DISPLAY INVISIBLE (4005 1030);
FORCEPROP 1 LAST OFFPAGE TRUE
J 0
(4375 1000);
DISPLAY 0.872340 (4375 1000);
PAINT GREEN (4375 1000);
DISPLAY INVISIBLE (4375 1000);
FORCEPROP 2 LAST CDS_LIB standard
J 0
(4050 1125);
DISPLAY INVISIBLE (4050 1125);
FORCEADD Q_RES..1
(2700 1225);
FORCEPROP 1 LAST LOCATION R3533
J 0
(2475 1225);
DISPLAY 0.638298 (2475 1225);
FORCEPROP 0 LAST $SEC 1
J 0
(2800 1350);
DISPLAY 0.680851 (2800 1350);
PAINT MONO (2800 1350);
DISPLAY INVISIBLE (2800 1350);
FORCEPROP 0 LAST CDS_SEC 1
J 0
(2800 1350);
DISPLAY 1.021277 (2800 1350);
DISPLAY INVISIBLE (2800 1350);
FORCEPROP 1 LASTPIN (2600 1225) $PN 1
J 0
(2612 1237);
DISPLAY 0.787234 (2612 1237);
PAINT MONO (2612 1237);
FORCEPROP 1 LASTPIN (2800 1225) $PN 2
J 0
(2762 1237);
DISPLAY 0.787234 (2762 1237);
PAINT MONO (2762 1237);
FORCEPROP 1 LAST MATERIAL CHIP
J 0
(3000 1225);
DISPLAY 0.510638 (3000 1225);
FORCEPROP 1 LAST WATTAGE 1/16W
J 2
(2800 1325);
DISPLAY 0.404255 (2800 1325);
FORCEPROP 1 LAST PACK_TYPE 0402LF
J 0
(2575 1325);
DISPLAY 0.404255 (2575 1325);
FORCEPROP 1 LAST VALUE 33.2
J 2
(2900 1225);
DISPLAY 0.510638 (2900 1225);
FORCEPROP 1 LAST TOLERANCE 1%
J 0
(2925 1225);
DISPLAY 0.510638 (2925 1225);
FORCEPROP 1 LAST PART_NUMBER CS03322FB03
J 0
(2575 1275);
DISPLAY 0.404255 (2575 1275);
DISPLAY INVISIBLE (2575 1275);
FORCEPROP 1 LAST PATH I76
J 0
(2650 1375);
DISPLAY 0.978723 (2650 1375);
PAINT WHITE (2650 1375);
DISPLAY INVISIBLE (2650 1375);
FORCEPROP 2 LAST CDS_LIB pure_quanta
J 0
(2700 1225);
DISPLAY INVISIBLE (2700 1225);
FORCEADD Q_RES..1
(2700 1125);
FORCEPROP 1 LAST LOCATION R3534
J 0
(2475 1125);
DISPLAY 0.638298 (2475 1125);
FORCEPROP 0 LAST $SEC 1
J 0
(2475 1175);
DISPLAY 0.680851 (2475 1175);
PAINT MONO (2475 1175);
DISPLAY INVISIBLE (2475 1175);
FORCEPROP 0 LAST CDS_SEC 1
J 0
(2475 1175);
DISPLAY 1.021277 (2475 1175);
DISPLAY INVISIBLE (2475 1175);
FORCEPROP 1 LASTPIN (2600 1125) $PN 1
J 0
(2612 1137);
DISPLAY 0.787234 (2612 1137);
PAINT MONO (2612 1137);
FORCEPROP 1 LASTPIN (2800 1125) $PN 2
J 0
(2762 1137);
DISPLAY 0.787234 (2762 1137);
PAINT MONO (2762 1137);
FORCEPROP 1 LAST TOLERANCE 1%
J 0
(2925 1125);
DISPLAY 0.510638 (2925 1125);
FORCEPROP 1 LAST VALUE 33.2
J 2
(2900 1125);
DISPLAY 0.510638 (2900 1125);
FORCEPROP 1 LAST MATERIAL CHIP
J 0
(3000 1125);
DISPLAY 0.510638 (3000 1125);
FORCEPROP 1 LAST PART_NUMBER CS03322FB03
J 0
(2575 1175);
DISPLAY 0.404255 (2575 1175);
DISPLAY INVISIBLE (2575 1175);
FORCEPROP 1 LAST PATH I77
J 0
(2650 1275);
DISPLAY 0.978723 (2650 1275);
PAINT WHITE (2650 1275);
DISPLAY INVISIBLE (2650 1275);
FORCEPROP 1 LAST WATTAGE 1/16W
J 2
(2800 1225);
DISPLAY 0.404255 (2800 1225);
DISPLAY INVISIBLE (2800 1225);
FORCEPROP 1 LAST PACK_TYPE 0402LF
J 0
(2575 1225);
DISPLAY 0.404255 (2575 1225);
DISPLAY INVISIBLE (2575 1225);
FORCEPROP 2 LAST CDS_LIB pure_quanta
J 0
(2700 1125);
DISPLAY INVISIBLE (2700 1125);
FORCEADD Q_RES..2
(2375 1575);
FORCEPROP 1 LAST LOCATION R3532
J 0
(2420 1700);
DISPLAY 0.638298 (2420 1700);
FORCEPROP 2 LAST $SEC 1
J 0
(2425 1800);
DISPLAY 0.680851 (2425 1800);
PAINT MONO (2425 1800);
DISPLAY INVISIBLE (2425 1800);
FORCEPROP 2 LAST CDS_SEC 1
J 0
(2425 1800);
DISPLAY 1.021277 (2425 1800);
DISPLAY INVISIBLE (2425 1800);
FORCEPROP 1 LASTPIN (2375 1675) $PN 1
J 0
(2380 1637);
DISPLAY 0.787234 (2380 1637);
FORCEPROP 1 LASTPIN (2375 1475) $PN 2
J 0
(2380 1485);
DISPLAY 0.787234 (2380 1485);
FORCEPROP 1 LAST VALUE 4.7K
J 0
(2420 1650);
DISPLAY 0.638298 (2420 1650);
FORCEPROP 1 LAST TOLERANCE 5%
J 0
(2420 1600);
DISPLAY 0.638298 (2420 1600);
FORCEPROP 1 LAST PACK_TYPE 0402LF
J 0
(2415 1450);
DISPLAY 0.638298 (2415 1450);
FORCEPROP 1 LAST WATTAGE 1/16W
J 0
(2415 1550);
DISPLAY 0.638298 (2415 1550);
FORCEPROP 1 LAST MATERIAL CHIP
J 0
(2415 1500);
DISPLAY 0.638298 (2415 1500);
FORCEPROP 1 LAST PART_NUMBER CS24702JB10
J 0
(2415 1400);
DISPLAY 0.638298 (2415 1400);
DISPLAY INVISIBLE (2415 1400);
FORCEPROP 1 LAST PATH I78
J 0
(2425 1750);
DISPLAY 0.978723 (2425 1750);
PAINT WHITE (2425 1750);
DISPLAY INVISIBLE (2425 1750);
FORCEPROP 2 LAST CDS_LIB pure_quanta
J 0
(2375 1575);
PAINT MONO (2375 1575);
DISPLAY INVISIBLE (2375 1575);
FORCEADD Q_RES..2
(2125 1575);
FORCEPROP 1 LAST LOCATION R3530
J 0
(2170 1700);
DISPLAY 0.638298 (2170 1700);
FORCEPROP 2 LAST $SEC 1
J 0
(2175 1800);
DISPLAY 0.680851 (2175 1800);
PAINT MONO (2175 1800);
DISPLAY INVISIBLE (2175 1800);
FORCEPROP 2 LAST CDS_SEC 1
J 0
(2175 1800);
DISPLAY 1.021277 (2175 1800);
DISPLAY INVISIBLE (2175 1800);
FORCEPROP 1 LASTPIN (2125 1675) $PN 1
J 0
(2130 1637);
DISPLAY 0.787234 (2130 1637);
FORCEPROP 1 LASTPIN (2125 1475) $PN 2
J 0
(2130 1485);
DISPLAY 0.787234 (2130 1485);
FORCEPROP 1 LAST VALUE 4.7K
J 0
(2170 1650);
DISPLAY 0.638298 (2170 1650);
FORCEPROP 1 LAST MATERIAL CHIP
J 0
(2165 1500);
DISPLAY 0.638298 (2165 1500);
FORCEPROP 1 LAST PACK_TYPE 0402LF
J 0
(2165 1450);
DISPLAY 0.638298 (2165 1450);
FORCEPROP 1 LAST TOLERANCE 5%
J 0
(2170 1600);
DISPLAY 0.638298 (2170 1600);
FORCEPROP 1 LAST WATTAGE 1/16W
J 0
(2165 1550);
DISPLAY 0.638298 (2165 1550);
FORCEPROP 1 LAST PART_NUMBER CS24702JB10
J 0
(2165 1400);
DISPLAY 0.638298 (2165 1400);
DISPLAY INVISIBLE (2165 1400);
FORCEPROP 1 LAST PATH I80
J 0
(2175 1750);
DISPLAY 0.978723 (2175 1750);
PAINT WHITE (2175 1750);
DISPLAY INVISIBLE (2175 1750);
FORCEPROP 2 LAST CDS_LIB pure_quanta
J 0
(2125 1575);
PAINT MONO (2125 1575);
DISPLAY INVISIBLE (2125 1575);
FORCEADD Q_CAP..1
(1600 1650);
FORCEPROP 1 LAST LOCATION C1998
J 0
(1650 1750);
DISPLAY 0.978723 (1650 1750);
FORCEPROP 2 LAST $SEC 1
J 0
(1650 1850);
DISPLAY 0.680851 (1650 1850);
PAINT MONO (1650 1850);
DISPLAY INVISIBLE (1650 1850);
FORCEPROP 2 LAST CDS_SEC 1
J 0
(1650 1850);
DISPLAY 1.021277 (1650 1850);
DISPLAY INVISIBLE (1650 1850);
FORCEPROP 1 LASTPIN (1600 1750) $PN 1
J 0
(1610 1730);
DISPLAY 0.787234 (1610 1730);
FORCEPROP 1 LASTPIN (1600 1550) $PN 2
J 0
(1610 1530);
DISPLAY 0.787234 (1610 1530);
FORCEPROP 1 LAST PACK_TYPE 0402
J 0
(1650 1450);
DISPLAY 0.510638 (1650 1450);
FORCEPROP 1 LAST VOLTAGE 25V
J 0
(1650 1650);
DISPLAY 0.510638 (1650 1650);
FORCEPROP 1 LAST MATERIAL X7R
J 0
(1650 1550);
DISPLAY 0.510638 (1650 1550);
FORCEPROP 1 LAST TOLERANCE 10%
J 0
(1650 1600);
DISPLAY 0.510638 (1650 1600);
FORCEPROP 1 LAST VALUE 0.1UF
J 0
(1650 1700);
DISPLAY 0.510638 (1650 1700);
FORCEPROP 1 LAST PART_NUMBER CH4104K1B00
J 0
(1650 1500);
DISPLAY 0.510638 (1650 1500);
DISPLAY INVISIBLE (1650 1500);
FORCEPROP 1 LAST PATH I82
J 0
(1650 1800);
DISPLAY 0.978723 (1650 1800);
PAINT WHITE (1650 1800);
DISPLAY INVISIBLE (1650 1800);
FORCEPROP 2 LAST CDS_LIB pure_quanta
J 0
(1600 1650);
PAINT MONO (1600 1650);
DISPLAY INVISIBLE (1600 1650);
FORCEADD UNIVERSAL_GND..1
(1600 1425);
FORCEPROP 3 LASTPIN (1600 1475) SIG_NAME GND\g
J 0
(1610 1485);
DISPLAY 0.659574 (1610 1485);
PAINT MONO (1610 1485);
DISPLAY INVISIBLE (1610 1485);
FORCEPROP 1 LAST PATH I84
J 0
(1675 1425);
DISPLAY 0.872340 (1675 1425);
PAINT AQUA (1675 1425);
DISPLAY INVISIBLE (1675 1425);
FORCEPROP 1 LAST HDL_POWER GND
J 1
(1625 1350);
DISPLAY 0.872340 (1625 1350);
PAINT GREEN (1625 1350);
DISPLAY INVISIBLE (1625 1350);
FORCEPROP 2 LAST CDS_LIB pure_quanta_power
J 0
(1600 1425);
PAINT MONO (1600 1425);
DISPLAY INVISIBLE (1600 1425);
FORCEADD UNIVERSAL_POWER..1
(75 1975);
FORCEPROP 3 LASTPIN (75 1925) SIG_NAME P3V3_AUX\g
J 0
(85 1935);
DISPLAY 0.659574 (85 1935);
PAINT MONO (85 1935);
DISPLAY INVISIBLE (85 1935);
FORCEPROP 1 LAST HDL_POWER P3V3_AUX
J 1
(75 2025);
DISPLAY 0.872340 (75 2025);
PAINT GREEN (75 2025);
FORCEPROP 1 LAST PATH I87
J 0
(125 2000);
DISPLAY 0.872340 (125 2000);
PAINT AQUA (125 2000);
DISPLAY INVISIBLE (125 2000);
FORCEPROP 2 LAST CDS_LIB pure_quanta_power
J 0
(75 1975);
PAINT MONO (75 1975);
DISPLAY INVISIBLE (75 1975);
FORCEADD Q_CAP..1
R 2
(-350 1625);
FORCEPROP 1 LAST LOCATION C1997
J 2
(-400 1725);
DISPLAY 0.978723 (-400 1725);
FORCEPROP 2 LAST $SEC 1
J 0
(-400 1825);
DISPLAY 0.680851 (-400 1825);
PAINT MONO (-400 1825);
DISPLAY INVISIBLE (-400 1825);
FORCEPROP 2 LAST CDS_SEC 1
J 0
(-400 1825);
DISPLAY 1.021277 (-400 1825);
DISPLAY INVISIBLE (-400 1825);
FORCEPROP 1 LASTPIN (-350 1725) $PN 1
J 2
(-360 1705);
DISPLAY 0.787234 (-360 1705);
FORCEPROP 1 LASTPIN (-350 1525) $PN 2
J 2
(-360 1505);
DISPLAY 0.787234 (-360 1505);
FORCEPROP 1 LAST PACK_TYPE 0402
J 2
(-400 1425);
DISPLAY 0.510638 (-400 1425);
FORCEPROP 1 LAST VOLTAGE 25V
J 2
(-400 1625);
DISPLAY 0.510638 (-400 1625);
FORCEPROP 1 LAST VALUE 0.1UF
J 2
(-400 1675);
DISPLAY 0.510638 (-400 1675);
FORCEPROP 1 LAST TOLERANCE 10%
J 2
(-400 1575);
DISPLAY 0.510638 (-400 1575);
FORCEPROP 1 LAST MATERIAL X7R
J 2
(-400 1525);
DISPLAY 0.510638 (-400 1525);
FORCEPROP 1 LAST PART_NUMBER CH4104K1B00
J 2
(-400 1475);
DISPLAY 0.510638 (-400 1475);
DISPLAY INVISIBLE (-400 1475);
FORCEPROP 1 LAST PATH I89
J 2
(-400 1775);
DISPLAY 0.978723 (-400 1775);
PAINT WHITE (-400 1775);
DISPLAY INVISIBLE (-400 1775);
FORCEPROP 2 LAST CDS_LIB pure_quanta
J 2
(-350 1625);
PAINT MONO (-350 1625);
DISPLAY INVISIBLE (-350 1625);
FORCEADD UNIVERSAL_GND..1
(-350 1425);
FORCEPROP 3 LASTPIN (-350 1475) SIG_NAME GND\g
J 0
(-340 1485);
DISPLAY 0.659574 (-340 1485);
PAINT MONO (-340 1485);
DISPLAY INVISIBLE (-340 1485);
FORCEPROP 1 LAST PATH I90
J 0
(-275 1425);
DISPLAY 0.872340 (-275 1425);
PAINT AQUA (-275 1425);
DISPLAY INVISIBLE (-275 1425);
FORCEPROP 1 LAST HDL_POWER GND
J 1
(-325 1350);
DISPLAY 0.872340 (-325 1350);
PAINT GREEN (-325 1350);
DISPLAY INVISIBLE (-325 1350);
FORCEPROP 2 LAST CDS_LIB pure_quanta_power
J 0
(-350 1425);
PAINT MONO (-350 1425);
DISPLAY INVISIBLE (-350 1425);
FORCEADD OFFPAGE..6
(-925 1125);
FORCEPROP 2 LAST $XR0 251 
J 0
(-1205 1125);
DISPLAY 0.638298 (-1205 1125);
PAINT MONO (-1205 1125);
FORCEPROP 2 LAST PATH I91
J 0
(-1200 1175);
DISPLAY 1.021277 (-1200 1175);
DISPLAY INVISIBLE (-1200 1175);
FORCEPROP 1 LAST COMMENT_BODY TRUE
J 0
(-825 1050);
DISPLAY 0.872340 (-825 1050);
PAINT GREEN (-825 1050);
DISPLAY INVISIBLE (-825 1050);
FORCEPROP 1 LAST OFFPAGE TRUE
J 0
(-600 1000);
DISPLAY 0.872340 (-600 1000);
DISPLAY INVISIBLE (-600 1000);
FORCEPROP 2 LAST CDS_LIB standard
J 0
(-925 1125);
PAINT MONO (-925 1125);
DISPLAY INVISIBLE (-925 1125);
FORCEADD OFFPAGE..1
(-925 1225);
FORCEPROP 2 LAST $XR0 251 
J 0
(-1177 1225);
DISPLAY 0.638298 (-1177 1225);
PAINT MONO (-1177 1225);
FORCEPROP 2 LAST PATH I92
J 0
(-1200 1275);
DISPLAY 1.021277 (-1200 1275);
DISPLAY INVISIBLE (-1200 1275);
FORCEPROP 1 LAST COMMENT_BODY TRUE
J 0
(-800 1125);
DISPLAY 0.872340 (-800 1125);
PAINT GREEN (-800 1125);
DISPLAY INVISIBLE (-800 1125);
FORCEPROP 1 LAST OFFPAGE TRUE
J 0
(-600 1100);
DISPLAY 0.872340 (-600 1100);
DISPLAY INVISIBLE (-600 1100);
FORCEPROP 2 LAST CDS_LIB standard
J 0
(-925 1225);
PAINT MONO (-925 1225);
DISPLAY INVISIBLE (-925 1225);
FORCEADD PCA9617ADP..1
R 2
(850 1175);
FORCEPROP 1 LAST LOCATION U279
J 2
(1124 1585);
DISPLAY 0.723404 (1124 1585);
PAINT GREEN (1124 1585);
FORCEPROP 0 LAST $SEC 1
J 0
(1100 1725);
DISPLAY 0.680851 (1100 1725);
PAINT MONO (1100 1725);
DISPLAY INVISIBLE (1100 1725);
FORCEPROP 0 LAST CDS_SEC 1
J 0
(1100 1725);
DISPLAY 1.021277 (1100 1725);
DISPLAY INVISIBLE (1100 1725);
FORCEPROP 0 LASTPIN (425 975) $PN 5
J 2
(415 985);
DISPLAY 0.680851 (415 985);
PAINT MONO (415 985);
FORCEPROP 0 LASTPIN (1275 975) $PN 4
J 0
(1285 985);
DISPLAY 0.680851 (1285 985);
PAINT MONO (1285 985);
FORCEPROP 0 LASTPIN (1275 1225) $PN 2
J 0
(1285 1235);
DISPLAY 0.680851 (1285 1235);
PAINT MONO (1285 1235);
FORCEPROP 0 LASTPIN (425 1225) $PN 7
J 2
(415 1235);
DISPLAY 0.680851 (415 1235);
PAINT MONO (415 1235);
FORCEPROP 0 LASTPIN (1275 1125) $PN 3
J 0
(1285 1135);
DISPLAY 0.680851 (1285 1135);
PAINT MONO (1285 1135);
FORCEPROP 0 LASTPIN (425 1125) $PN 6
J 2
(415 1135);
DISPLAY 0.680851 (415 1135);
PAINT MONO (415 1135);
FORCEPROP 0 LASTPIN (1275 1375) $PN 1
J 0
(1285 1385);
DISPLAY 0.680851 (1285 1385);
PAINT MONO (1285 1385);
FORCEPROP 0 LASTPIN (425 1375) $PN 8
J 2
(415 1385);
DISPLAY 0.680851 (415 1385);
PAINT MONO (415 1385);
FORCEPROP 1 LAST MATERIAL IC
J 2
(1124 1480);
DISPLAY 0.723404 (1124 1480);
PAINT GREEN (1124 1480);
FORCEPROP 2 LAST PART_TYPE SMLF
J 2
(1100 1675);
DISPLAY 1.021277 (1100 1675);
FORCEPROP 2 LAST VALUE PCA9617ADP
J 2
(1100 1625);
DISPLAY 1.021277 (1100 1625);
FORCEPROP 1 LAST PART_NUMBER AL009617K02
J 2
(1124 1535);
DISPLAY 0.723404 (1124 1535);
PAINT GREEN (1124 1535);
DISPLAY INVISIBLE (1124 1535);
FORCEPROP 1 LAST PATH I93
J 2
(850 1175);
DISPLAY 0.723404 (850 1175);
PAINT GREEN (850 1175);
DISPLAY INVISIBLE (850 1175);
FORCEPROP 1 LAST NEEDS_NO_SIZE TRUE
J 2
(575 875);
DISPLAY 0.468085 (575 875);
PAINT GREEN (575 875);
DISPLAY INVISIBLE (575 875);
FORCEPROP 1 LAST CDS_LMAN_SYM_OUTLINE -275,300,275,-300
J 2
(850 1175);
DISPLAY 0.468085 (850 1175);
PAINT GREEN (850 1175);
DISPLAY INVISIBLE (850 1175);
FORCEPROP 2 LAST CDS_LIB pure_quanta
J 2
(850 1175);
DISPLAY INVISIBLE (850 1175);
FORCEADD OFFPAGE..4
R 2
(-2300 975);
FORCEPROP 2 LAST $XR0 145 
J 0
(-2582 975);
DISPLAY 0.638298 (-2582 975);
PAINT MONO (-2582 975);
FORCEPROP 2 LAST PATH I94
J 2
(-2850 1025);
DISPLAY 1.021277 (-2850 1025);
DISPLAY INVISIBLE (-2850 1025);
FORCEPROP 1 LAST COMMENT_BODY TRUE
J 2
(-2275 875);
DISPLAY 0.872340 (-2275 875);
PAINT GREEN (-2275 875);
DISPLAY INVISIBLE (-2275 875);
FORCEPROP 1 LAST OFFPAGE TRUE
J 2
(-2625 850);
DISPLAY 0.872340 (-2625 850);
DISPLAY INVISIBLE (-2625 850);
FORCEPROP 2 LAST CDS_LIB standard
J 2
(-2300 975);
DISPLAY INVISIBLE (-2300 975);
FORCEADD UNIVERSAL_GND..1
(1450 850);
FORCEPROP 3 LASTPIN (1450 900) SIG_NAME GND\g
J 0
(1460 910);
DISPLAY 0.659574 (1460 910);
PAINT MONO (1460 910);
DISPLAY INVISIBLE (1460 910);
FORCEPROP 1 LAST PATH I95
J 0
(1525 850);
DISPLAY 0.872340 (1525 850);
PAINT AQUA (1525 850);
DISPLAY INVISIBLE (1525 850);
FORCEPROP 1 LAST HDL_POWER GND
J 1
(1475 775);
DISPLAY 0.872340 (1475 775);
PAINT GREEN (1475 775);
DISPLAY INVISIBLE (1475 775);
FORCEPROP 2 LAST CDS_LIB pure_quanta_power
J 0
(1450 850);
PAINT MONO (1450 850);
DISPLAY INVISIBLE (1450 850);
FORCEADD Q_RES..1
(-1500 975);
FORCEPROP 1 LAST LOCATION R3531
J 0
(-1725 975);
DISPLAY 0.787234 (-1725 975);
FORCEPROP 0 LAST $SEC 1
J 0
(-1300 1125);
DISPLAY 0.680851 (-1300 1125);
PAINT MONO (-1300 1125);
DISPLAY INVISIBLE (-1300 1125);
FORCEPROP 0 LAST CDS_SEC 1
J 0
(-1300 1125);
DISPLAY 1.021277 (-1300 1125);
DISPLAY INVISIBLE (-1300 1125);
FORCEPROP 1 LASTPIN (-1600 975) $PN 1
J 0
(-1588 987);
DISPLAY 0.787234 (-1588 987);
PAINT MONO (-1588 987);
FORCEPROP 1 LASTPIN (-1400 975) $PN 2
J 0
(-1438 987);
DISPLAY 0.787234 (-1438 987);
PAINT MONO (-1438 987);
FORCEPROP 1 LAST MATERIAL EMPTY
J 0
(-1200 975);
DISPLAY 0.510638 (-1200 975);
PAINT RED (-1200 975);
FORCEPROP 1 LAST TOLERANCE 1%
J 0
(-1275 975);
DISPLAY 0.510638 (-1275 975);
FORCEPROP 1 LAST VALUE 200K
J 2
(-1300 975);
DISPLAY 0.510638 (-1300 975);
FORCEPROP 1 LAST WATTAGE 1/16W
J 2
(-1325 1075);
DISPLAY 0.510638 (-1325 1075);
FORCEPROP 1 LAST PACK_TYPE 0402LF
J 0
(-1600 1075);
DISPLAY 0.510638 (-1600 1075);
FORCEPROP 1 LAST PART_NUMBER CS42002FB05
J 0
(-1600 1050);
DISPLAY 0.510638 (-1600 1050);
DISPLAY INVISIBLE (-1600 1050);
FORCEPROP 1 LAST PATH I96
J 0
(-1550 1125);
DISPLAY 0.978723 (-1550 1125);
PAINT WHITE (-1550 1125);
DISPLAY INVISIBLE (-1550 1125);
FORCEPROP 2 LAST CDS_LIB pure_quanta
J 0
(-1500 975);
DISPLAY INVISIBLE (-1500 975);
FORCEADD UNIVERSAL_POWER..1
(1425 1950);
FORCEPROP 3 LASTPIN (1425 1900) SIG_NAME P3V3_E1S_0\g
J 0
(1435 1910);
DISPLAY 0.659574 (1435 1910);
PAINT MONO (1435 1910);
DISPLAY INVISIBLE (1435 1910);
FORCEPROP 1 LAST HDL_POWER P3V3_E1S_0
J 1
(1425 2000);
DISPLAY 0.872340 (1425 2000);
PAINT GREEN (1425 2000);
FORCEPROP 1 LAST PATH I97
J 0
(1475 1975);
DISPLAY 0.872340 (1475 1975);
PAINT AQUA (1475 1975);
DISPLAY INVISIBLE (1475 1975);
FORCEPROP 2 LAST CDS_LIB pure_quanta_power
J 0
(1425 1950);
DISPLAY INVISIBLE (1425 1950);
FORCEADD UNIVERSAL_POWER..1
(2125 1900);
FORCEPROP 3 LASTPIN (2125 1850) SIG_NAME P3V3_E1S_0\g
J 0
(2135 1860);
DISPLAY 0.659574 (2135 1860);
PAINT MONO (2135 1860);
DISPLAY INVISIBLE (2135 1860);
FORCEPROP 1 LAST HDL_POWER P3V3_E1S_0
J 1
(2125 1950);
DISPLAY 0.872340 (2125 1950);
PAINT GREEN (2125 1950);
FORCEPROP 1 LAST PATH I98
J 0
(2175 1925);
DISPLAY 0.872340 (2175 1925);
PAINT AQUA (2175 1925);
DISPLAY INVISIBLE (2175 1925);
FORCEPROP 2 LAST CDS_LIB pure_quanta_power
J 0
(2125 1900);
DISPLAY INVISIBLE (2125 1900);
FORCEADD Q_RES..2
(-25 1600);
FORCEPROP 1 LAST LOCATION R3529
J 0
(25 1675);
DISPLAY 0.638298 (25 1675);
FORCEPROP 0 LAST $SEC 1
J 0
(25 1725);
DISPLAY 0.680851 (25 1725);
PAINT MONO (25 1725);
DISPLAY INVISIBLE (25 1725);
FORCEPROP 0 LAST CDS_SEC 1
J 0
(25 1725);
DISPLAY 1.021277 (25 1725);
DISPLAY INVISIBLE (25 1725);
FORCEPROP 1 LASTPIN (-25 1700) $PN 1
J 0
(-20 1662);
DISPLAY 0.787234 (-20 1662);
PAINT MONO (-20 1662);
FORCEPROP 1 LASTPIN (-25 1500) $PN 2
J 0
(-20 1510);
DISPLAY 0.787234 (-20 1510);
PAINT MONO (-20 1510);
FORCEPROP 1 LAST TOLERANCE 1%
J 0
(25 1625);
DISPLAY 0.510638 (25 1625);
FORCEPROP 1 LAST PACK_TYPE 0402LF
J 0
(25 1525);
DISPLAY 0.510638 (25 1525);
FORCEPROP 1 LAST MATERIAL CHIP
J 0
(25 1575);
DISPLAY 0.510638 (25 1575);
FORCEPROP 1 LAST WATTAGE 1/16W
J 0
(25 1600);
DISPLAY 0.510638 (25 1600);
FORCEPROP 1 LAST VALUE 10K
J 0
(25 1650);
DISPLAY 0.510638 (25 1650);
FORCEPROP 1 LAST PART_NUMBER CS31002FB08
J 0
(25 1550);
DISPLAY 0.510638 (25 1550);
DISPLAY INVISIBLE (25 1550);
FORCEPROP 1 LAST PATH I99
J 0
(25 1775);
DISPLAY 0.978723 (25 1775);
PAINT WHITE (25 1775);
DISPLAY INVISIBLE (25 1775);
FORCEPROP 2 LAST CDS_LIB pure_quanta
J 0
(-25 1600);
DISPLAY INVISIBLE (-25 1600);
FORCEADD DNS..2
(-1475 975);
PAINT RED (-1475 975);
FORCEPROP 1 LAST COMMENT_BODY TRUE
J 0
(-1475 975);
DISPLAY INVISIBLE (-1475 975);
FORCEPROP 2 LAST CDS_LIB mstr_misc
J 0
(-1475 975);
DISPLAY INVISIBLE (-1475 975);
FORCEADD QUANTA_TITLE_BLOCK_C..1
(5950 -1750);
FORCEPROP 0 LAST CDS_CON_LAST_MODIFIED Thu Sep 14 16:12:28 2023
J 0
(4065 -1735);
PAINT MONO (4065 -1735);
DISPLAY INVISIBLE (4065 -1735);
FORCEPROP 1 LAST CUSTOM_TXT_CDS <CON_LAST_MODIFIED>
J 0
(4065 -1735);
DISPLAY 0.978723 (4065 -1735);
FORCEPROP 2 LAST CUSTOM_TXT_CDS <XR_PAGE_TITLE>
J 0
(-1940 3500);
DISPLAY 0.638298 (-1940 3500);
PAINT PINK (-1940 3500);
DISPLAY INVISIBLE (-1940 3500);
FORCEPROP 1 LAST CUSTOM_TXT_CDS <NAME_2>
J 0
(2775 -1700);
FORCEPROP 1 LAST CUSTOM_TXT_CDS <NAME_1>
J 0
(2775 -1575);
FORCEPROP 1 LAST CUSTOM_TXT_CDS <Q_NUMBER>
J 0
(4547 -1647);
DISPLAY 1.212766 (4547 -1647);
FORCEPROP 1 LAST CUSTOM_TXT_CDS <Q_PROJ>
J 0
(3568 -1648);
DISPLAY 1.212766 (3568 -1648);
FORCEPROP 1 LAST CUSTOM_TXT_CDS <Q_REV>
J 0
(5766 -1647);
DISPLAY 1.212766 (5766 -1647);
FORCEPROP 1 LAST CUSTOM_TXT_CDS <CON_PAGE_NUM> OF <CON_TOTAL_PAGES>
J 0
(5504 -1732);
DISPLAY 0.978723 (5504 -1732);
FORCEPROP 1 LAST Q_TITLE CPU - SATA / RAID KEY
J 0
(-3341 -1724);
DISPLAY 2.446809 (-3341 -1724);
PAINT GREEN (-3341 -1724);
FORCEPROP 1 LAST COMMENT_BODY TRUE
J 0
(5962 -1763);
DISPLAY 0.978723 (5962 -1763);
PAINT GREEN (5962 -1763);
DISPLAY INVISIBLE (5962 -1763);
FORCEPROP 1 LAST Q_DEPT BU9
J 1
(2187 -1701);
DISPLAY 1.957447 (2187 -1701);
PAINT GREEN (2187 -1701);
DISPLAY INVISIBLE (2187 -1701);
FORCEPROP 2 LAST CDS_XR_PAGE_TITLE CR-148 : @T6G_MB_LIB.T6G(SCH_1):PAGE148
J 0
(-1940 3500);
DISPLAY 0.638298 (-1940 3500);
PAINT PINK (-1940 3500);
DISPLAY INVISIBLE (-1940 3500);
FORCEPROP 2 LAST CDS_LIB pure_quanta
J 0
(5950 -1750);
PAINT MONO (5950 -1750);
DISPLAY INVISIBLE (5950 -1750);
FORCEPROP 1 LAST CDS_LMAN_SYM_OUTLINE -9475,6775,100,-125
J 0
(5950 -1750);
DISPLAY 0.468085 (5950 -1750);
PAINT GREEN (5950 -1750);
DISPLAY INVISIBLE (5950 -1750);
FORCEPROP 2 LAST PAGE_BORDER TRUE
J 0
(-1940 3500);
DISPLAY 0.638298 (-1940 3500);
PAINT PINK (-1940 3500);
DISPLAY INVISIBLE (-1940 3500);
FORCEADD DNS..2
(2325 3100);
PAINT RED (2325 3100);
FORCEPROP 1 LAST COMMENT_BODY TRUE
J 0
(2325 3100);
DISPLAY INVISIBLE (2325 3100);
FORCEPROP 2 LAST CDS_LIB mstr_misc
J 0
(2325 3100);
DISPLAY INVISIBLE (2325 3100);
WIRE 16 -1 (1400 3700)(1400 3625);
WIRE 16 -1 (-425 3675)(-425 3625);
WIRE 16 -1 (1600 1550)(1600 1475);
WIRE 16 -1 (-350 1525)(-350 1475);
WIRE 16 -1 (425 1375)(350 1375);
WIRE 16 -1 (350 1800)(350 1375);
WIRE 16 -1 (75 1800)(350 1800);
WIRE 16 -1 (75 1925)(75 1800);
WIRE 16 -1 (-25 1800)(75 1800);
WIRE 16 -1 (-25 1800)(-25 1700);
WIRE 16 -1 (-350 1800)(-25 1800);
WIRE 16 -1 (-350 1725)(-350 1800);
WIRE 16 -1 (1225 3975)(1225 3525);
WIRE 16 -1 (1225 3975)(1400 3975);
WIRE 16 -1 (1225 3975)(1225 4050);
WIRE 16 -1 (1225 3525)(1075 3525);
WIRE 16 -1 (1400 3900)(1400 3975);
WIRE 16 -1 (475 3275)(350 3275);
FORCEPROP 0 LAST VOLTAGE 0
J 0
(400 3275);
DISPLAY INVISIBLE (400 3275);
WIRE 16 -1 (350 3200)(350 3275);
WIRE 16 -1 (2500 3875)(2500 4000);
WIRE 16 -1 (2250 4000)(2500 4000);
WIRE 16 -1 (2250 3875)(2250 4000);
WIRE 16 -1 (2250 4000)(2250 4050);
WIRE 16 -1 (-425 3875)(-425 3950);
WIRE 16 -1 (-425 3950)(0 3950);
WIRE 16 -1 (0 3950)(0 3850);
WIRE 16 -1 (0 4075)(0 3950);
WIRE 16 -1 (1275 975)(1450 975);
WIRE 16 -1 (1450 900)(1450 975);
WIRE 16 -1 (1425 1825)(1425 1375);
WIRE 16 -1 (1425 1825)(1600 1825);
WIRE 16 -1 (1425 1825)(1425 1900);
WIRE 16 -1 (1425 1375)(1275 1375);
WIRE 16 -1 (1600 1750)(1600 1825);
WIRE 16 -1 (2375 1675)(2375 1800);
WIRE 16 -1 (2125 1800)(2375 1800);
WIRE 16 -1 (2125 1675)(2125 1800);
WIRE 16 -1 (2125 1800)(2125 1850);
WIRE 16 -1 (4075 3425)(2900 3425);
FORCEPROP 0 LAST CDS_PHYS_NET_NAME SMB_SENSOR_M2_P0_3V3AUX_SCL
J 0
(3015 3473);
PAINT MONO (3015 3473);
DISPLAY INVISIBLE (3015 3473);
FORCEPROP 2 LAST SIG_NAME SMB_M2_P1_1V8AUX_SDA
J 0
(3465 3435);
DISPLAY 0.510638 (3465 3435);
PAINT WHITE (3465 3435);
WIRE 16 -1 (4075 3375)(2900 3375);
FORCEPROP 0 LAST CDS_PHYS_NET_NAME SMB_SENSOR_M2_P0_3V3AUX_SDA
J 0
(3015 3423);
PAINT MONO (3015 3423);
DISPLAY INVISIBLE (3015 3423);
FORCEPROP 2 LAST SIG_NAME SMB_M2_P1_1V8AUX_SCL
J 0
(3465 3385);
DISPLAY 0.510638 (3465 3385);
PAINT WHITE (3465 3385);
WIRE 16 -1 (3575 3100)(2400 3100);
FORCEPROP 0 LAST CDS_PHYS_NET_NAME SMB_SENSOR_M2_P0_3V3AUX_SDA
J 0
(2515 3148);
PAINT MONO (2515 3148);
DISPLAY INVISIBLE (2515 3148);
FORCEPROP 2 LAST SIG_NAME PWRGD_P1V8_AUX_R
J 0
(2965 3110);
DISPLAY 0.510638 (2965 3110);
PAINT WHITE (2965 3110);
WIRE 16 -1 (2700 3425)(2250 3425);
WIRE 16 -1 (2250 3675)(2250 3425);
WIRE 16 -1 (2250 3425)(1075 3425);
FORCEPROP 0 LAST CDS_PHYS_NET_NAME SMB_SENSOR_M2_P0_3V3AUX_SCL
J 0
(1190 3473);
PAINT MONO (1190 3473);
DISPLAY INVISIBLE (1190 3473);
FORCEPROP 2 LAST SIG_NAME SMB_M2_P1_1V8AUX_SDA_R
J 0
(1225 3435);
DISPLAY 0.510638 (1225 3435);
PAINT WHITE (1225 3435);
FORCEPROP 2 LASTPROP $XRERR UNIQUE?
J 0
(985 3435);
DISPLAY 0.638298 (985 3435);
PAINT MONO (985 3435);
DISPLAY INVISIBLE (985 3435);
WIRE 16 -1 (2700 3375)(2500 3375);
WIRE 16 -1 (2500 3675)(2500 3375);
WIRE 16 -1 (2500 3375)(1075 3375);
FORCEPROP 0 LAST CDS_PHYS_NET_NAME SMB_SENSOR_M2_P0_3V3AUX_SDA
J 0
(1190 3423);
PAINT MONO (1190 3423);
DISPLAY INVISIBLE (1190 3423);
FORCEPROP 2 LAST SIG_NAME SMB_M2_P1_1V8AUX_SCL_R
J 0
(1225 3385);
DISPLAY 0.510638 (1225 3385);
PAINT WHITE (1225 3385);
FORCEPROP 2 LASTPROP $XRERR UNIQUE?
J 0
(985 3385);
DISPLAY 0.638298 (985 3385);
PAINT MONO (985 3385);
DISPLAY INVISIBLE (985 3385);
WIRE 16 -1 (0 3650)(0 3525);
WIRE 16 -1 (375 3525)(0 3525);
WIRE 16 -1 (0 3525)(0 3100);
WIRE 16 -1 (0 3100)(1975 3100);
WIRE 16 -1 (2200 3100)(1975 3100);
WIRE 16 -1 (1975 3100)(1975 3275);
WIRE 16 -1 (1075 3275)(1975 3275);
FORCEPROP 0 LAST CDS_PHYS_NET_NAME SMB_SENSOR_M2_P0_3V3AUX_SDA
J 0
(1190 3323);
PAINT MONO (1190 3323);
DISPLAY INVISIBLE (1190 3323);
FORCEPROP 2 LAST SIG_NAME SMB_PCIE_M2_0_EN
J 0
(1225 3285);
DISPLAY 0.510638 (1225 3285);
PAINT WHITE (1225 3285);
FORCEPROP 2 LASTPROP $XRERR UNIQUE?
J 0
(985 3285);
DISPLAY 0.638298 (985 3285);
PAINT MONO (985 3285);
DISPLAY INVISIBLE (985 3285);
WIRE 16 -1 (375 3425)(-950 3425);
FORCEPROP 0 LAST CDS_PHYS_NET_NAME SMB_SENSOR_M2_P0_3V3AUX_SCL
J 0
(-835 3473);
PAINT MONO (-835 3473);
DISPLAY INVISIBLE (-835 3473);
FORCEPROP 2 LAST SIG_NAME SMB_SENSOR_M2_P1_3V3AUX_SDA
J 2
(-160 3435);
DISPLAY 0.510638 (-160 3435);
PAINT WHITE (-160 3435);
WIRE 16 -1 (375 3375)(-950 3375);
FORCEPROP 0 LAST CDS_PHYS_NET_NAME SMB_SENSOR_M2_P0_3V3AUX_SDA
J 0
(-835 3423);
PAINT MONO (-835 3423);
DISPLAY INVISIBLE (-835 3423);
FORCEPROP 2 LAST SIG_NAME SMB_SENSOR_M2_P1_3V3AUX_SCL
J 2
(-160 3385);
DISPLAY 0.510638 (-160 3385);
PAINT WHITE (-160 3385);
WIRE 16 -1 (2600 1125)(2375 1125);
WIRE 16 -1 (2375 1475)(2375 1125);
WIRE 16 -1 (2375 1125)(1275 1125);
FORCEPROP 0 LAST CDS_PHYS_NET_NAME SMB_SENSOR_M2_P0_3V3AUX_SDA
J 0
(2015 1173);
PAINT MONO (2015 1173);
DISPLAY INVISIBLE (2015 1173);
FORCEPROP 2 LAST SIG_NAME SMB_E1S_3V3AUX_ISO_SDA_R
J 0
(1490 1135);
DISPLAY 0.510638 (1490 1135);
PAINT WHITE (1490 1135);
FORCEPROP 2 LASTPROP $XRERR UNIQUE?
J 0
(1250 1135);
DISPLAY 0.638298 (1250 1135);
PAINT MONO (1250 1135);
DISPLAY INVISIBLE (1250 1135);
WIRE 16 -1 (425 975)(-25 975);
WIRE 16 -1 (-25 1500)(-25 975);
WIRE 16 -1 (-25 975)(-1400 975);
FORCEPROP 0 LAST CDS_PHYS_NET_NAME SMB_PCIE_M2_1_EN
J 0
(-460 1023);
PAINT MONO (-460 1023);
DISPLAY INVISIBLE (-460 1023);
FORCEPROP 2 LAST SIG_NAME SMB_PCIE_E1S_ISO_EN_R
J 0
(-710 985);
DISPLAY 0.510638 (-710 985);
PAINT WHITE (-710 985);
FORCEPROP 2 LASTPROP $XRERR UNIQUE?
J 0
(-950 985);
DISPLAY 0.638298 (-950 985);
PAINT MONO (-950 985);
DISPLAY INVISIBLE (-950 985);
WIRE 16 -1 (2600 1225)(2125 1225);
WIRE 16 -1 (2125 1475)(2125 1225);
WIRE 16 -1 (2125 1225)(1275 1225);
FORCEPROP 0 LAST CDS_PHYS_NET_NAME SMB_SENSOR_M2_P0_3V3AUX_SCL
J 0
(1490 1273);
PAINT MONO (1490 1273);
DISPLAY INVISIBLE (1490 1273);
FORCEPROP 2 LAST SIG_NAME SMB_E1S_3V3AUX_ISO_SCL_R
J 0
(1490 1235);
DISPLAY 0.510638 (1490 1235);
PAINT WHITE (1490 1235);
FORCEPROP 2 LASTPROP $XRERR UNIQUE?
J 0
(1250 1235);
DISPLAY 0.638298 (1250 1235);
PAINT MONO (1250 1235);
DISPLAY INVISIBLE (1250 1235);
WIRE 16 -1 (425 1125)(-875 1125);
FORCEPROP 0 LAST CDS_PHYS_NET_NAME SMB_SENSOR_M2_P0_3V3AUX_SCL
J 0
(-760 1173);
PAINT MONO (-760 1173);
DISPLAY INVISIBLE (-760 1173);
FORCEPROP 2 LAST SIG_NAME SMB_SENSOR_E1S_3V3AUX_SDA
J 2
(-110 1135);
DISPLAY 0.510638 (-110 1135);
PAINT WHITE (-110 1135);
WIRE 16 -1 (425 1225)(-875 1225);
FORCEPROP 0 LAST CDS_PHYS_NET_NAME SMB_SENSOR_M2_P0_3V3AUX_SDA
J 0
(-760 1273);
PAINT MONO (-760 1273);
DISPLAY INVISIBLE (-760 1273);
FORCEPROP 2 LAST SIG_NAME SMB_SENSOR_E1S_3V3AUX_SCL
J 2
(-110 1235);
DISPLAY 0.510638 (-110 1235);
PAINT WHITE (-110 1235);
WIRE 16 -1 (4000 1225)(2800 1225);
FORCEPROP 0 LAST CDS_PHYS_NET_NAME SMB_SENSOR_M2_P0_3V3AUX_SCL
J 0
(2915 1273);
PAINT MONO (2915 1273);
DISPLAY INVISIBLE (2915 1273);
FORCEPROP 2 LAST SIG_NAME SMB_E1S_3V3AUX_ISO_SCL
J 0
(3365 1235);
DISPLAY 0.510638 (3365 1235);
PAINT WHITE (3365 1235);
WIRE 16 -1 (4000 1125)(2800 1125);
FORCEPROP 0 LAST CDS_PHYS_NET_NAME SMB_SENSOR_M2_P0_3V3AUX_SDA
J 0
(2915 1173);
PAINT MONO (2915 1173);
DISPLAY INVISIBLE (2915 1173);
FORCEPROP 2 LAST SIG_NAME SMB_E1S_3V3AUX_ISO_SDA
J 0
(3365 1135);
DISPLAY 0.510638 (3365 1135);
PAINT WHITE (3365 1135);
WIRE 16 -1 (-1600 975)(-2250 975);
FORCEPROP 0 LAST CDS_PHYS_NET_NAME PWRGD_P1V8_PCH_AUX
J 0
(-2135 1023);
PAINT MONO (-2135 1023);
DISPLAY INVISIBLE (-2135 1023);
FORCEPROP 2 LAST SIG_NAME SMB_PCIE_E1S_ISO_EN
J 0
(-2235 985);
DISPLAY 0.510638 (-2235 985);
PAINT WHITE (-2235 985);
DOT 1 (75 1800);
DOT 1 (-25 1800);
DOT 1 (2250 3425);
DOT 1 (0 3525);
DOT 1 (1225 3975);
DOT 1 (1975 3100);
DOT 1 (2500 3375);
DOT 1 (2250 4000);
DOT 1 (1425 1825);
DOT 1 (2125 1225);
DOT 1 (2375 1125);
DOT 1 (2125 1800);
DOT 1 (0 3950);
DOT 1 (-25 975);
CIRCLE (1800 4225)(1990 4225);
PAINT YELLOW (1800 4225);
FORCENOTE
TBC
(1750 4250) 0;
DISPLAY LEFT (1750 4250);
DISPLAY 1.021277 (1750 4250);
QUIT
